# S9S_MB_2U (Grand Teton) — schematic parts with pin connectivity, parts 1600–1600 of 6093; source: Cadence DE-HDL packaged netlist (pstxprt.dat, pstxnet.dat, pstchip.dat)

J7  SCONN288_ADR50017P130CC  SCONN288_ADR50017-P130CC IO  pkg DDR288S_1-1VXB  page 88
  1  VIN_BULK0  POWER  = P12V_S3_AUX_CPU0_NVDIMM
  2  RFU0  TRI  = TP_CHD_CPU0_DIMM1_FRU_0
  3  VIN_MGMT  POWER  = P3V3_AUX
  4  HSCL  IN  = I3C_SPD_DDRABCD_CPU0_LVC1_SCL_6
  5  HSDA  BI  = I3C_SPD_DDRABCD_CPU0_LVC1_SDA
  6  VSS0  POWER  = GND
  7  DQ0_A  BI  = M_D_CPU0_SA_DQ<0>
  8  VSS1  POWER  = GND
  9  DQ1_A  BI  = M_D_CPU0_SA_DQ<1>
  10  VSS2  POWER  = GND
  11  DQS0_A_T  BI  = M_D_CPU0_SA_DQS_DP<0>
  12  DQS0_A_C  BI  = M_D_CPU0_SA_DQS_DN<0>
  13  VSS3  POWER  = GND
  14  DQ4_A  BI  = M_D_CPU0_SA_DQ<4>
  15  VSS4  POWER  = GND
  16  DQ5_A  BI  = M_D_CPU0_SA_DQ<5>
  17  VSS5  POWER  = GND
  18  DQ8_A  BI  = M_D_CPU0_SA_DQ<8>
  19  VSS6  POWER  = GND
  20  DQ9_A  BI  = M_D_CPU0_SA_DQ<9>
  21  VSS7  POWER  = GND
  22  DQS1_A_T  BI  = M_D_CPU0_SA_DQS_DP<1>
  23  DQS1_A_C  BI  = M_D_CPU0_SA_DQS_DN<1>
  24  VSS8  POWER  = GND
  25  DQ12_A  BI  = M_D_CPU0_SA_DQ<12>
  26  VSS9  POWER  = GND
  27  DQ13_A  BI  = M_D_CPU0_SA_DQ<13>
  28  VSS10  POWER  = GND
  29  DQ16_A  BI  = M_D_CPU0_SA_DQ<16>
  30  VSS11  POWER  = GND
  31  DQ17_A  BI  = M_D_CPU0_SA_DQ<17>
  32  VSS12  POWER  = GND
  33  DQS2_A_T  BI  = M_D_CPU0_SA_DQS_DP<2>
  34  DQS2_A_C  BI  = M_D_CPU0_SA_DQS_DN<2>
  35  VSS13  POWER  = GND
  36  DQ20_A  BI  = M_D_CPU0_SA_DQ<20>
  37  VSS14  POWER  = GND
  38  DQ21_A  BI  = M_D_CPU0_SA_DQ<21>
  39  VSS15  POWER  = GND
  40  DQ24_A  BI  = M_D_CPU0_SA_DQ<24>
  41  VSS16  POWER  = GND
  42  DQ25_A  BI  = M_D_CPU0_SA_DQ<25>
  43  VSS17  POWER  = GND
  44  DQS3_A_T  BI  = M_D_CPU0_SA_DQS_DP<3>
  45  DQS3_A_C  BI  = M_D_CPU0_SA_DQS_DN<3>
  46  VSS18  POWER  = GND
  47  DQ28_A  BI  = M_D_CPU0_SA_DQ<28>
  48  VSS19  POWER  = GND
  49  DQ29_A  BI  = M_D_CPU0_SA_DQ<29>
  50  VSS20  POWER  = GND
  51  CB0_A  BI  = M_D_CPU0_SA_CB<0>
  52  VSS21  POWER  = GND
  53  CB1_A  BI  = M_D_CPU0_SA_CB<1>
  54  VSS22  POWER  = GND
  55  DQS4_A_T  BI  = M_D_CPU0_SA_DQS_DP<4>
  56  DQS4_A_C  BI  = M_D_CPU0_SA_DQS_DN<4>
  57  VSS23  POWER  = GND
  58  CB4_A  BI  = M_D_CPU0_SA_CB<4>
  59  VSS24  POWER  = GND
  60  CB5_A  BI  = M_D_CPU0_SA_CB<5>
  61  VSS25  POWER  = GND
  62  ALERT_N  OUT  = M_D_CPU0_ALERT_N
  63  VSS26  POWER  = GND
  64  CS0_A_N  IN  = M_D_CPU0_SA_CS_N<0>
  65  VSS27  POWER  = GND
  66  CA0_A  IN  = M_D_CPU0_SA_CA<0>
  67  VSS28  POWER  = GND
  68  CA2_A  IN  = M_D_CPU0_SA_CA<2>
  69  VSS29  POWER  = GND
  70  CA4_A  IN  = M_D_CPU0_SA_CA<4>
  71  VSS30  POWER  = GND
  72  CA6_A  IN  = M_D_CPU0_SA_CA<6>
  73  VSS31  POWER  = GND
  74  PAR_A  IN  = M_D_CPU0_SA_PAR
  75  VSS32  POWER  = GND
  76  CA0_B  IN  = M_D_CPU0_SB_CA<0>
  77  VSS33  POWER  = GND
  78  CA2_B  IN  = M_D_CPU0_SB_CA<2>
  79  VSS34  POWER  = GND
  80  CA4_B  IN  = M_D_CPU0_SB_CA<4>
  81  VSS35  POWER  = GND
  82  CA6_B  IN  = M_D_CPU0_SB_CA<6>
  83  VSS36  POWER  = GND
  84  CS0_B_N  IN  = M_D_CPU0_SB_CS_N<0>
  85  VSS37  POWER  = GND
  86  \lbd||rsp_a_n\  OUT  = M_D_CPU0_SA_RSP<0>
  87  \lbs||rsp_b_n\  OUT  = M_D_CPU0_SB_RSP<0>
  88  VSS38  POWER  = GND
  89  CB4_B  BI  = M_D_CPU0_SB_CB<4>
  90  VSS39  POWER  = GND
  91  CB5_B  BI  = M_D_CPU0_SB_CB<5>
  92  VSS40  POWER  = GND
  93  \dqs9_b_t||tdqs9_b_t||dbi4_b_n\  BI  = M_D_CPU0_SB_DQS_DP<9>
  94  \dqs9_b_c||tdqs9_b_c\  BI  = M_D_CPU0_SB_DQS_DN<9>
  95  VSS41  POWER  = GND
  96  CB0_B  BI  = M_D_CPU0_SB_CB<0>
  97  VSS42  POWER  = GND
  98  CB1_B  BI  = M_D_CPU0_SB_CB<1>
  99  VSS43  POWER  = GND
  100  DQ0_B  BI  = M_D_CPU0_SB_DQ<0>
  101  VSS44  POWER  = GND
  102  DQ1_B  BI  = M_D_CPU0_SB_DQ<1>
  103  VSS45  POWER  = GND
  104  DQS0_B_T  BI  = M_D_CPU0_SB_DQS_DP<0>
  105  DQS0_B_C  BI  = M_D_CPU0_SB_DQS_DN<0>
  106  VSS46  POWER  = GND
  107  DQ4_B  BI  = M_D_CPU0_SB_DQ<4>
  108  VSS47  POWER  = GND
  109  DQ5_B  BI  = M_D_CPU0_SB_DQ<5>
  110  VSS48  POWER  = GND
  111  DQ8_B  BI  = M_D_CPU0_SB_DQ<8>
  112  VSS49  POWER  = GND
  113  DQ9_B  BI  = M_D_CPU0_SB_DQ<9>
  114  VSS50  POWER  = GND
  115  DQS1_B_T  BI  = M_D_CPU0_SB_DQS_DP<1>
  116  DQS1_B_C  BI  = M_D_CPU0_SB_DQS_DN<1>
  117  VSS51  POWER  = GND
  118  DQ12_B  BI  = M_D_CPU0_SB_DQ<12>
  119  VSS52  POWER  = GND
  120  DQ13_B  BI  = M_D_CPU0_SB_DQ<13>
  121  VSS53  POWER  = GND
  122  DQ16_B  BI  = M_D_CPU0_SB_DQ<16>
  123  VSS54  POWER  = GND
  124  DQ17_B  BI  = M_D_CPU0_SB_DQ<17>
  125  VSS55  POWER  = GND
  126  DQS2_B_T  BI  = M_D_CPU0_SB_DQS_DP<2>
  127  DQS2_B_C  BI  = M_D_CPU0_SB_DQS_DN<2>
  128  VSS56  POWER  = GND
  129  DQ20_B  BI  = M_D_CPU0_SB_DQ<20>
  130  VSS57  POWER  = GND
  131  DQ21_B  BI  = M_D_CPU0_SB_DQ<21>
  132  VSS58  POWER  = GND
  133  DQ24_B  BI  = M_D_CPU0_SB_DQ<24>
  134  VSS59  POWER  = GND
  135  DQ25_B  BI  = M_D_CPU0_SB_DQ<25>
  136  VSS60  POWER  = GND
  137  DQS3_B_T  BI  = M_D_CPU0_SB_DQS_DP<3>
  138  DQS3_B_C  BI  = M_D_CPU0_SB_DQS_DN<3>
  139  VSS61  POWER  = GND
  140  DQ28_B  BI  = M_D_CPU0_SB_DQ<28>
  141  VSS62  POWER  = GND
  142  DQ29_B  BI  = M_D_CPU0_SB_DQ<29>
  143  VSS63  POWER  = GND
  144  RFU1  TRI  = TP_CHD_CPU0_DIMM1_FRU_1
  145  VIN_BULK1  POWER  = P12V_S3_AUX_CPU0_NVDIMM
  146  VIN_BULK2  POWER  = P12V_S3_AUX_CPU0_NVDIMM
  147  \pwr_good||fail_n\  BI  = PWRGD_CHD_CPU0_DIMM1
  148  HSA  IN  = PD_CHD_CPU0_DIMM1_SAA
  149  RFU2  TRI  = TP_CHD_CPU0_DIMM1_FRU_2
  150  RFU3  TRI  = TP_CHD_CPU0_DIMM1_FRU_3
  151  VSS64  POWER  = GND
  152  DQ2_A  BI  = M_D_CPU0_SA_DQ<2>
  153  VSS65  POWER  = GND
  154  DQ3_A  BI  = M_D_CPU0_SA_DQ<3>
  155  VSS66  POWER  = GND
  156  \dqs5_a_c||tdqs5_a_c||dqs5_a_t||tdqs5_a_t\  BI  = M_D_CPU0_SA_DQS_DN<5>
  157  \dqs5_a_t||tdqs5_a_t\  BI  = M_D_CPU0_SA_DQS_DP<5>
  158  VSS67  POWER  = GND
  159  DQ6_A  BI  = M_D_CPU0_SA_DQ<6>
  160  VSS68  POWER  = GND
  161  DQ7_A  BI  = M_D_CPU0_SA_DQ<7>
  162  VSS69  POWER  = GND
  163  DQ10_A  BI  = M_D_CPU0_SA_DQ<10>
  164  VSS70  POWER  = GND
  165  DQ11_A  BI  = M_D_CPU0_SA_DQ<11>
  166  VSS71  POWER  = GND
  167  \dqs6_a_c||tdqs6_a_c||dqs6_a_t||tdqs6_a_t\  BI  = M_D_CPU0_SA_DQS_DN<6>
  168  \dqs6_a_t||tdqs6_a_t\  BI  = M_D_CPU0_SA_DQS_DP<6>
  169  VSS72  POWER  = GND
  170  DQ14_A  BI  = M_D_CPU0_SA_DQ<14>
  171  VSS73  POWER  = GND
  172  DQ15_A  BI  = M_D_CPU0_SA_DQ<15>
  173  VSS74  POWER  = GND
  174  DQ18_A  BI  = M_D_CPU0_SA_DQ<18>
  175  VSS75  POWER  = GND
  176  DQ19_A  BI  = M_D_CPU0_SA_DQ<19>
  177  VSS76  POWER  = GND
  178  \dqs7_a_c||tdqs7_a_c\  BI  = M_D_CPU0_SA_DQS_DN<7>
  179  \dqs7_a_t||tdqs7_a_t\  BI  = M_D_CPU0_SA_DQS_DP<7>
  180  VSS77  POWER  = GND
  181  DQ22_A  BI  = M_D_CPU0_SA_DQ<22>
  182  VSS78  POWER  = GND
  183  DQ23_A  BI  = M_D_CPU0_SA_DQ<23>
  184  VSS79  POWER  = GND
  185  DQ26_A  BI  = M_D_CPU0_SA_DQ<26>
  186  VSS80  POWER  = GND
  187  DQ27_A  BI  = M_D_CPU0_SA_DQ<27>
  188  VSS81  POWER  = GND
  189  \dqs8_a_c||tdqs8_a_c\  BI  = M_D_CPU0_SA_DQS_DN<8>
  190  \dqs8_a_t||tdqs8_a_t\  BI  = M_D_CPU0_SA_DQS_DP<8>
  191  VSS82  POWER  = GND
  192  DQ30_A  BI  = M_D_CPU0_SA_DQ<30>
  193  VSS83  POWER  = GND
  194  DQ31_A  BI  = M_D_CPU0_SA_DQ<31>
  195  VSS84  POWER  = GND
  196  CB2_A  BI  = M_D_CPU0_SA_CB<2>
  197  VSS85  POWER  = GND
  198  CB3_A  BI  = M_D_CPU0_SA_CB<3>
  199  VSS86  POWER  = GND
  200  \dqs9_a_c||tdqs9_a_c\  BI  = M_D_CPU0_SA_DQS_DN<9>
  201  \dqs9_a_t||tdqs9_a_t\  BI  = M_D_CPU0_SA_DQS_DP<9>
  202  VSS87  POWER  = GND
  203  CB6_A  BI  = M_D_CPU0_SA_CB<6>
  204  VSS88  POWER  = GND
  205  CB7_A  BI  = M_D_CPU0_SA_CB<7>
  206  VSS89  POWER  = GND
  207  RESET_N  IN  = RST_M_CD_CPU0_FPGA_N
  208  VSS90  POWER  = GND
  209  CS1_A_N  IN  = M_D_CPU0_SA_CS_N<1>
  210  VSS91  POWER  = GND
  211  CA1_A  IN  = M_D_CPU0_SA_CA<1>
  212  VSS92  POWER  = GND
  213  CA3_A  IN  = M_D_CPU0_SA_CA<3>
  214  VSS93  POWER  = GND
  215  CA5_A  IN  = M_D_CPU0_SA_CA<5>
  216  VSS94  POWER  = GND
  217  CK_T  IN  = M_D_CPU0_CLK_DP<0>
  218  CK_C  IN  = M_D_CPU0_CLK_DN<0>
  219  VSS95  POWER  = GND
  220  RFU4  TRI  = TP_CHD_CPU0_DIMM1_FRU_4
  221  CA1_B  IN  = M_D_CPU0_SB_CA<1>
  222  VSS96  POWER  = GND
  223  CA3_B  IN  = M_D_CPU0_SB_CA<3>
  224  VSS97  POWER  = GND
  225  CA5_B  IN  = M_D_CPU0_SB_CA<5>
  226  VSS98  POWER  = GND
  227  PAR_B  IN  = M_D_CPU0_SB_PAR
  228  VSS99  POWER  = GND
  229  CS1_B_N  IN  = M_D_CPU0_SB_CS_N<1>
  230  VSS100  POWER  = GND
  231  RFU5  TRI  = TP_CHD_CPU0_DIMM1_FRU_5
  232  RFU6  TRI  = TP_CHD_CPU0_DIMM1_FRU_6
  233  VSS101  POWER  = GND
  234  CB6_B  BI  = M_D_CPU0_SB_CB<6>
  235  VSS102  POWER  = GND
  236  CB7_B  BI  = M_D_CPU0_SB_CB<7>
  237  VSS103  POWER  = GND
  238  DQS4_B_C  BI  = M_D_CPU0_SB_DQS_DN<4>
  239  DQS4_B_T  BI  = M_D_CPU0_SB_DQS_DP<4>
  240  VSS104  POWER  = GND
  241  CB2_B  BI  = M_D_CPU0_SB_CB<2>
  242  VSS105  POWER  = GND
  243  CB3_B  BI  = M_D_CPU0_SB_CB<3>
  244  VSS106  POWER  = GND
  245  DQ2_B  BI  = M_D_CPU0_SB_DQ<2>
  246  VSS107  POWER  = GND
  247  DQ3_B  BI  = M_D_CPU0_SB_DQ<3>
  248  VSS108  POWER  = GND
  249  \dqs5_b_c||tdqs5_b_c\  BI  = M_D_CPU0_SB_DQS_DN<5>
  250  \dqs5_b_t||tdqs5_b_t\  BI  = M_D_CPU0_SB_DQS_DP<5>
  251  VSS109  POWER  = GND
  252  DQ6_B  BI  = M_D_CPU0_SB_DQ<6>
  253  VSS110  POWER  = GND
  254  DQ7_B  BI  = M_D_CPU0_SB_DQ<7>
  255  VSS111  POWER  = GND
  256  DQ10_B  BI  = M_D_CPU0_SB_DQ<10>
  257  VSS112  POWER  = GND
  258  DQ11_B  BI  = M_D_CPU0_SB_DQ<11>
  259  VSS113  POWER  = GND
  260  \dqs6_b_c||tdqs6_b_c\  BI  = M_D_CPU0_SB_DQS_DN<6>
  261  \dqs6_b_t||tdqs6_b_t\  BI  = M_D_CPU0_SB_DQS_DP<6>
  262  VSS114  POWER  = GND
  263  DQ14_B  BI  = M_D_CPU0_SB_DQ<14>
  264  VSS115  POWER  = GND
  265  DQ15_B  BI  = M_D_CPU0_SB_DQ<15>
  266  VSS116  POWER  = GND
  267  DQ18_B  BI  = M_D_CPU0_SB_DQ<18>
  268  VSS117  POWER  = GND
  269  DQ19_B  BI  = M_D_CPU0_SB_DQ<19>
  270  VSS118  POWER  = GND
  271  \dqs7_b_c||tdqs7_b_c\  BI  = M_D_CPU0_SB_DQS_DN<7>
  272  \dqs7_b_t||tdqs7_b_t\  BI  = M_D_CPU0_SB_DQS_DP<7>
  273  VSS119  POWER  = GND
  274  DQ22_B  BI  = M_D_CPU0_SB_DQ<22>
  275  VSS120  POWER  = GND
  276  DQ23_B  BI  = M_D_CPU0_SB_DQ<23>
  277  VSS121  POWER  = GND
  278  DQ26_B  BI  = M_D_CPU0_SB_DQ<26>
  279  VSS122  POWER  = GND
  280  DQ27_B  BI  = M_D_CPU0_SB_DQ<27>
  281  VSS123  POWER  = GND
  282  \dqs8_b_c||tdqs8_b_c\  BI  = M_D_CPU0_SB_DQS_DN<8>
  283  \dqs8_b_t||tdqs8_b_t\  BI  = M_D_CPU0_SB_DQS_DP<8>
  284  VSS124  POWER  = GND
  285  DQ30_B  BI  = M_D_CPU0_SB_DQ<30>
  286  VSS125  POWER  = GND
  287  DQ31_B  BI  = M_D_CPU0_SB_DQ<31>
  288  VSS126  POWER  = GND
  G1  G1  POWER  = GND
  G2  G2  POWER  = GND
  G3  G3  POWER  = GND
